# TIMECARD (Time Appliance Project (Time Card)) — schematic netlist excerpt (pin names and nets, part order shuffled) for the footprints in the layout excerpt that follows; sources: Cadence DE-HDL packaged netlist, KiCad conversion of R4006-B0001-02_R01.brd

R492  RESISTOR  0OHM -  pkg SMC_0402R_H016  page 23 : \1\ = UNNAMED_12_CAPACITOR_I318_2 ; \2\ = UNNAMED_12_74HCT2G125DPTSSOP8_I
C219  CAPACITOR  0.1UF 10V 10%  pkg SMC_0402R_H022  page 14 : \1\ = XP1R8V_FPGA_VCCAUX ; \2\ = SG

(kicad_pcb
	(version 20260206)
	(generator "pcbnew")
	(generator_version "10.0")
	(general
		(thickness 1.6)
		(legacy_teardrops no)
	)
	(paper "A4")
	(title_block
		(title "timecard-production-celestica-r4006 — R4006-B0001-02_R01.brd")
		(comment 1 "Time Appliance Project (Time Card) / footprints 1112-1113 of 1113")
	)
	(layers
		(0 "F.Cu" signal "TOP")
		(4 "In1.Cu" signal "L02_GND1")
		(6 "In2.Cu" signal "L03_SIG1")
		(8 "In3.Cu" signal "L04_GND2")
		(10 "In4.Cu" signal "L05_VCC1")
		(12 "In5.Cu" signal "L06_VCC2")
		(14 "In6.Cu" signal "L07_GND3")
		(16 "In7.Cu" signal "L08_SIG2")
		(18 "In8.Cu" signal "L09_GND4")
		(2 "B.Cu" signal "BOTTOM")
		(9 "F.Adhes" user "F.Adhesive")
		(11 "B.Adhes" user "B.Adhesive")
		(13 "F.Paste" user "Package Geometry/Pastemask Top")
		(15 "B.Paste" user "Package Geometry/Pastemask Bottom")
		(5 "F.SilkS" user "Ref Des/Silkscreen Top")
		(7 "B.SilkS" user "Ref Des/Silkscreen Bottom")
		(1 "F.Mask" user "Board Geometry/Soldermask Top")
		(3 "B.Mask" user "Board Geometry/Soldermask Bottom")
		(17 "Dwgs.User" user "User.Drawings")
		(19 "Cmts.User" user "User.Comments")
		(21 "Eco1.User" user "User.Eco1")
		(23 "Eco2.User" user "User.Eco2")
		(25 "Edge.Cuts" user "Board Geometry/Outline")
		(27 "Margin" user)
		(31 "F.CrtYd" user "Package Geometry/Place Bound Top")
		(29 "B.CrtYd" user "Package Geometry/Place Bound Bottom")
		(35 "F.Fab" user "Ref Des/Assembly Top")
		(33 "B.Fab" user "Ref Des/Assembly Bottom")
	)
	(footprint ""
		(layer "B.Cu")
		(at 13.462 -37.211 90)
		(property "Reference" "R492"
			(at -1.524 1.73863 270)
			(unlocked yes)
			(layer "B.SilkS")
			(effects
				(font
					(size 0.7874 0.5842)
					(thickness 0.1524)
				)
				(justify mirror)
			)
		)
		(property "Value" "VAL*"
			(at -0.02032 2.13233 90)
			(unlocked yes)
			(layer "B.Fab")
			(hide yes)
			(effects
				(font
					(size 0.7874 0.5842)
					(thickness 0.1524)
				)
				(justify mirror)
			)
		)
		(property "Tolerance" "TOL*"
			(at -0.044704 3.05435 90)
			(unlocked yes)
			(layer "Cmts.User")
			(hide yes)
			(effects
				(font
					(size 0.7874 0.5842)
					(thickness 0.1524)
				)
				(justify mirror)
			)
		)
		(property "User Part Number" "PARTNUM*"
			(at -0.02032 4.024884 90)
			(unlocked yes)
			(layer "Cmts.User")
			(hide yes)
			(effects
				(font
					(size 0.7874 0.5842)
					(thickness 0.1524)
				)
				(justify mirror)
			)
		)
		(property "Device Type" "RESISTOR-G155-100R0-J0,0OHM,-"
			(at -0.008382 1.210564 90)
			(unlocked yes)
			(layer "B.Fab")
			(hide yes)
			(effects
				(font
					(size 0.7874 0.5842)
					(thickness 0.1524)
				)
				(justify mirror)
			)
		)
		(duplicate_pad_numbers_are_jumpers no)
		(fp_line
			(start 1.143 -0.5588)
			(end 1.143 0.5588)
			(stroke
				(width 0.1)
				(type default)
			)
			(layer "B.SilkS")
		)
		(fp_line
			(start -1.143 -0.5588)
			(end 1.143 -0.5588)
			(stroke
				(width 0.1)
				(type default)
			)
			(layer "B.SilkS")
		)
		(fp_line
			(start 1.143 0.5588)
			(end -1.143 0.5588)
			(stroke
				(width 0.1)
				(type default)
			)
			(layer "B.SilkS")
		)
		(fp_line
			(start -1.143 0.5588)
			(end -1.143 -0.5588)
			(stroke
				(width 0.1)
				(type default)
			)
			(layer "B.SilkS")
		)
		(fp_poly
			(pts
				(xy 1.143 0.5588) (xy -1.143 0.5588) (xy -1.143 -0.5588) (xy 1.143 -0.5588)
			)
			(stroke
				(width 0)
				(type default)
			)
			(fill no)
			(layer "B.CrtYd")
		)
		(fp_line
			(start 0.508 -0.3048)
			(end 0.508 0.3048)
			(stroke
				(width 0.1)
				(type default)
			)
			(layer "B.Fab")
		)
		(fp_line
			(start -0.508 -0.3048)
			(end 0.508 -0.3048)
			(stroke
				(width 0.1)
				(type default)
			)
			(layer "B.Fab")
		)
		(fp_line
			(start 0.508 0.3048)
			(end -0.508 0.3048)
			(stroke
				(width 0.1)
				(type default)
			)
			(layer "B.Fab")
		)
		(fp_line
			(start -0.508 0.3048)
			(end -0.508 -0.3048)
			(stroke
				(width 0.1)
				(type default)
			)
			(layer "B.Fab")
		)
		(pad "1" smd rect
			(at 0.5334 0 270)
			(size 0.7112 0.6096)
			(layers "B.Cu" "B.Mask" "B.Paste")
			(net "UNNAMED_12_CAPACITOR_I318_2")
		)
		(pad "2" smd rect
			(at -0.5334 0 270)
			(size 0.7112 0.6096)
			(layers "B.Cu" "B.Mask" "B.Paste")
			(net "UNNAMED_12_74HCT2G125DPTSSOP8_I")
		)
		(zone
			(layer "B.Cu")
			(hatch none 0.5)
			(connect_pads
				(clearance 0)
			)
			(min_thickness 0.25)
			(keepout
				(tracks allowed)
				(vias not_allowed)
				(pads allowed)
				(copperpour not_allowed)
				(footprints allowed)
			)
			(placement
				(enabled no)
				(sheetname "")
			)
			(fill
				(thermal_gap 0.5)
				(thermal_bridge_width 0.5)
				(island_removal_mode 0)
			)
			(polygon
				(pts
					(xy 13.7668 -37.2872) (xy 13.1572 -37.2872) (xy 13.1572 -37.1348) (xy 13.7668 -37.1348)
				)
			)
		)
		(zone
			(layer "B.Cu")
			(hatch none 0.5)
			(connect_pads
				(clearance 0)
			)
			(min_thickness 0.25)
			(keepout
				(tracks not_allowed)
				(vias allowed)
				(pads allowed)
				(copperpour not_allowed)
				(footprints allowed)
			)
			(placement
				(enabled no)
				(sheetname "")
			)
			(fill
				(thermal_gap 0.5)
				(thermal_bridge_width 0.5)
				(island_removal_mode 0)
			)
			(polygon
				(pts
					(xy 13.7668 -37.2872) (xy 13.1572 -37.2872) (xy 13.1572 -37.1348) (xy 13.7668 -37.1348)
				)
			)
		)
	)
	(footprint ""
		(layer "B.Cu")
		(at 107.188 -44.45)
		(property "Reference" "C219"
			(at -43.307 1.63195 0)
			(unlocked yes)
			(layer "B.SilkS")
			(effects
				(font
					(size 0.635 0.4064)
					(thickness 0.1524)
				)
				(justify mirror)
			)
		)
		(property "Value" "VAL*"
			(at -0.0762 2.067306 0)
			(unlocked yes)
			(layer "B.Fab")
			(hide yes)
			(effects
				(font
					(size 0.7874 0.5842)
					(thickness 0.1524)
				)
				(justify mirror)
			)
		)
		(property "Device Type" "CAPACITOR-G105-0B104-CK,0.1UF,A"
			(at -0.0508 1.127506 0)
			(unlocked yes)
			(layer "B.Fab")
			(hide yes)
			(effects
				(font
					(size 0.7874 0.5842)
					(thickness 0.1524)
				)
				(justify mirror)
			)
		)
		(property "User Part Number" "PARTNUM*"
			(at -0.1016 4.023106 0)
			(unlocked yes)
			(layer "Cmts.User")
			(hide yes)
			(effects
				(font
					(size 0.7874 0.5842)
					(thickness 0.1524)
				)
				(justify mirror)
			)
		)
		(property "Tolerance" "TOL*"
			(at -0.0762 3.032506 0)
			(unlocked yes)
			(layer "Cmts.User")
			(hide yes)
			(effects
				(font
					(size 0.7874 0.5842)
					(thickness 0.1524)
				)
				(justify mirror)
			)
		)
		(duplicate_pad_numbers_are_jumpers no)
		(fp_line
			(start -1.143 -0.5588)
			(end 1.143 -0.5588)
			(stroke
				(width 0.1)
				(type default)
			)
			(layer "B.SilkS")
		)
		(fp_line
			(start -1.143 0.5588)
			(end -1.143 -0.5588)
			(stroke
				(width 0.1)
				(type default)
			)
			(layer "B.SilkS")
		)
		(fp_line
			(start 1.143 -0.5588)
			(end 1.143 0.5588)
			(stroke
				(width 0.1)
				(type default)
			)
			(layer "B.SilkS")
		)
		(fp_line
			(start 1.143 0.5588)
			(end -1.143 0.5588)
			(stroke
				(width 0.1)
				(type default)
			)
			(layer "B.SilkS")
		)
		(fp_rect
			(start -1.143 0.5588)
			(end 1.143 -0.5588)
			(stroke
				(width 0)
				(type default)
			)
			(fill no)
			(layer "B.CrtYd")
		)
		(fp_line
			(start -0.508 -0.3048)
			(end 0.508 -0.3048)
			(stroke
				(width 0.1)
				(type default)
			)
			(layer "B.Fab")
		)
		(fp_line
			(start -0.508 0.3048)
			(end -0.508 -0.3048)
			(stroke
				(width 0.1)
				(type default)
			)
			(layer "B.Fab")
		)
		(fp_line
			(start 0.508 -0.3048)
			(end 0.508 0.3048)
			(stroke
				(width 0.1)
				(type default)
			)
			(layer "B.Fab")
		)
		(fp_line
			(start 0.508 0.3048)
			(end -0.508 0.3048)
			(stroke
				(width 0.1)
				(type default)
			)
			(layer "B.Fab")
		)
		(pad "1" smd rect
			(at 0.5334 0 180)
			(size 0.7112 0.6096)
			(layers "B.Cu" "B.Mask" "B.Paste")
			(net "XP1R8V_FPGA_VCCAUX")
		)
		(pad "2" smd rect
			(at -0.5334 0 180)
			(size 0.7112 0.6096)
			(layers "B.Cu" "B.Mask" "B.Paste")
			(net "SG")
		)
		(zone
			(layer "B.Cu")
			(hatch none 0.5)
			(connect_pads
				(clearance 0)
			)
			(min_thickness 0.25)
			(keepout
				(tracks allowed)
				(vias not_allowed)
				(pads allowed)
				(copperpour not_allowed)
				(footprints allowed)
			)
			(placement
				(enabled no)
				(sheetname "")
			)
			(fill
				(thermal_gap 0.5)
				(thermal_bridge_width 0.5)
				(island_removal_mode 0)
			)
			(polygon
				(pts
					(xy 107.1118 -44.1452) (xy 107.2642 -44.1452) (xy 107.2642 -44.7548) (xy 107.1118 -44.7548)
				)
			)
		)
	)
)
